(kicad_pcb
	(version 20240108)
	(generator "pcbnew")
	(generator_version "8.0")
	(general
		(thickness 1.62)
		(legacy_teardrops no)
	)
	(paper "A4")
	(title_block
		(title "Jetson Orin Baseboard")
		(date "2025-03-12")
		(rev "1.3.4")
		(company "Antmicro Ltd")
		(comment 1 "www.antmicro.com")
		(comment 9 "footprints 321-325 of 677")
	)
	(layers
		(0 "F.Cu" signal)
		(1 "In1.Cu" signal)
		(2 "In2.Cu" signal)
		(3 "In3.Cu" signal)
		(4 "In4.Cu" jumper)
		(5 "In5.Cu" signal)
		(6 "In6.Cu" signal)
		(31 "B.Cu" signal)
		(32 "B.Adhes" user "B.Adhesive")
		(33 "F.Adhes" user "F.Adhesive")
		(34 "B.Paste" user)
		(35 "F.Paste" user)
		(36 "B.SilkS" user "B.Silkscreen")
		(37 "F.SilkS" user "F.Silkscreen")
		(38 "B.Mask" user)
		(39 "F.Mask" user)
		(40 "Dwgs.User" user "User.Drawings")
		(41 "Cmts.User" user "User.Comments")
		(42 "Eco1.User" user "User.Eco1")
		(43 "Eco2.User" user "User.Eco2")
		(44 "Edge.Cuts" user)
		(45 "Margin" user)
		(46 "B.CrtYd" user "B.Courtyard")
		(47 "F.CrtYd" user "F.Courtyard")
		(48 "B.Fab" user)
		(49 "F.Fab" user)
	)
	(footprint "antmicro-footprints:R_0402_1005Metric"
		(layer "B.Cu")
		(at 91 81.4)
		(descr "Resistor SMD 0402")
		(tags "resistor SMD 0402")
		(property "Reference" "R10"
			(at 1.05 -0.45 180)
			(layer "B.SilkS")
			(effects
				(font
					(size 0.7 0.7)
					(thickness 0.15)
				)
				(justify left bottom mirror)
			)
		)
		(property "Value" "R_4k7_0402"
			(at 0 -1.4 180)
			(layer "B.Fab")
			(effects
				(font
					(size 0.7 0.7)
					(thickness 0.15)
				)
				(justify left bottom mirror)
			)
		)
		(property "Footprint" "antmicro-footprints:R_0402_1005Metric"
			(at 0 0 0)
			(layer "F.Fab")
			(hide yes)
			(effects
				(font
					(size 1.27 1.27)
					(thickness 0.15)
				)
			)
		)
		(property "Datasheet" "https://www.bourns.com/docs/product-datasheets/cr.pdf"
			(at 0 0 0)
			(layer "F.Fab")
			(hide yes)
			(effects
				(font
					(size 1.27 1.27)
					(thickness 0.15)
				)
			)
		)
		(property "Author" "Antmicro"
			(at 0 0 0)
			(layer "B.Fab")
			(hide yes)
			(effects
				(font
					(size 1 1)
					(thickness 0.15)
				)
				(justify mirror)
			)
		)
		(property "License" "Apache-2.0"
			(at 0 0 0)
			(layer "B.Fab")
			(hide yes)
			(effects
				(font
					(size 1 1)
					(thickness 0.15)
				)
				(justify mirror)
			)
		)
		(property "MPN" "CR0402-FX-4701GLF"
			(at 0 0 0)
			(layer "B.Fab")
			(hide yes)
			(effects
				(font
					(size 1 1)
					(thickness 0.15)
				)
				(justify mirror)
			)
		)
		(property "Manufacturer" "Bourns"
			(at 0 0 0)
			(layer "B.Fab")
			(hide yes)
			(effects
				(font
					(size 1 1)
					(thickness 0.15)
				)
				(justify mirror)
			)
		)
		(property "Tolerance" "1%"
			(at 0 0 0)
			(layer "B.Fab")
			(hide yes)
			(effects
				(font
					(size 1 1)
					(thickness 0.15)
				)
				(justify mirror)
			)
		)
		(property "Val" "4k7"
			(at 0 0 0)
			(layer "B.Fab")
			(hide yes)
			(effects
				(font
					(size 1 1)
					(thickness 0.15)
				)
				(justify mirror)
			)
		)
		(sheetname "CSI")
		(sheetfile "csi.kicad_sch")
		(attr smd)
		(fp_rect
			(start -0.925 0.47)
			(end 0.925 -0.47)
			(stroke
				(width 0.05)
				(type default)
			)
			(fill none)
			(layer "B.CrtYd")
		)
		(fp_rect
			(start -0.5 0.25)
			(end 0.5 -0.25)
			(stroke
				(width 0.15)
				(type solid)
			)
			(fill none)
			(layer "B.Fab")
		)
		(fp_text user "License: Apache-2.0"
			(at -0.95 -5.169 180)
			(layer "B.Fab")
			(hide yes)
			(effects
				(font
					(size 0.7 0.7)
					(thickness 0.15)
				)
				(justify left bottom mirror)
			)
		)
		(fp_text user "${REFERENCE}"
			(at -0.95 -3.168 180)
			(layer "B.Fab")
			(hide yes)
			(effects
				(font
					(size 0.7 0.7)
					(thickness 0.15)
				)
				(justify left bottom mirror)
			)
		)
		(fp_text user "Author: Antmicro"
			(at -0.95 -4.169 180)
			(layer "B.Fab")
			(hide yes)
			(effects
				(font
					(size 0.7 0.7)
					(thickness 0.15)
				)
				(justify left bottom mirror)
			)
		)
		(pad "1" smd roundrect
			(at -0.48 0)
			(size 0.59 0.64)
			(layers "B.Cu" "B.Paste" "B.Mask")
			(roundrect_rratio 0.25)
			(net 1 "GND")
			(pintype "passive")
		)
		(pad "2" smd roundrect
			(at 0.48 0)
			(size 0.59 0.64)
			(layers "B.Cu" "B.Paste" "B.Mask")
			(roundrect_rratio 0.25)
			(net 344 "/CSI/CSIB_3V3_ISET")
			(pintype "passive")
		)
	)
	(footprint "antmicro-footprints:R_0402_1005Metric"
		(layer "B.Cu")
		(at 89.9 118 90)
		(descr "Resistor SMD 0402")
		(tags "resistor SMD 0402")
		(property "Reference" "R281"
			(at 1.65 5.15 -90)
			(layer "B.SilkS")
			(effects
				(font
					(size 0.7 0.7)
					(thickness 0.15)
				)
				(justify left bottom mirror)
			)
		)
		(property "Value" "R_2k2_0402"
			(at 0 -1.4 -90)
			(layer "B.Fab")
			(effects
				(font
					(size 0.7 0.7)
					(thickness 0.15)
				)
				(justify left bottom mirror)
			)
		)
		(property "Footprint" "antmicro-footprints:R_0402_1005Metric"
			(at 0 0 90)
			(layer "F.Fab")
			(hide yes)
			(effects
				(font
					(size 1.27 1.27)
					(thickness 0.15)
				)
			)
		)
		(property "Datasheet" "https://www.bourns.com/docs/product-datasheets/cr.pdf"
			(at 0 0 90)
			(layer "F.Fab")
			(hide yes)
			(effects
				(font
					(size 1.27 1.27)
					(thickness 0.15)
				)
			)
		)
		(property "Author" "Antmicro"
			(at 207.9 28.1 0)
			(layer "B.Fab")
			(hide yes)
			(effects
				(font
					(size 1 1)
					(thickness 0.15)
				)
				(justify mirror)
			)
		)
		(property "License" "Apache-2.0"
			(at 207.9 28.1 0)
			(layer "B.Fab")
			(hide yes)
			(effects
				(font
					(size 1 1)
					(thickness 0.15)
				)
				(justify mirror)
			)
		)
		(property "MPN" "CR0402-FX-2201GLF"
			(at 207.9 28.1 0)
			(layer "B.Fab")
			(hide yes)
			(effects
				(font
					(size 1 1)
					(thickness 0.15)
				)
				(justify mirror)
			)
		)
		(property "Manufacturer" "Bourns"
			(at 207.9 28.1 0)
			(layer "B.Fab")
			(hide yes)
			(effects
				(font
					(size 1 1)
					(thickness 0.15)
				)
				(justify mirror)
			)
		)
		(property "Tolerance" "1%"
			(at 207.9 28.1 0)
			(layer "B.Fab")
			(hide yes)
			(effects
				(font
					(size 1 1)
					(thickness 0.15)
				)
				(justify mirror)
			)
		)
		(property "Val" "2k2"
			(at 207.9 28.1 0)
			(layer "B.Fab")
			(hide yes)
			(effects
				(font
					(size 1 1)
					(thickness 0.15)
				)
				(justify mirror)
			)
		)
		(sheetname "HDMI")
		(sheetfile "hdmi.kicad_sch")
		(attr smd exclude_from_pos_files exclude_from_bom dnp)
		(fp_rect
			(start -0.925 0.47)
			(end 0.925 -0.47)
			(stroke
				(width 0.05)
				(type default)
			)
			(fill none)
			(layer "B.CrtYd")
		)
		(fp_rect
			(start -0.5 0.25)
			(end 0.5 -0.25)
			(stroke
				(width 0.15)
				(type solid)
			)
			(fill none)
			(layer "B.Fab")
		)
		(fp_text user "${REFERENCE}"
			(at -0.95 -3.168 -90)
			(layer "B.Fab")
			(hide yes)
			(effects
				(font
					(size 0.7 0.7)
					(thickness 0.15)
				)
				(justify left bottom mirror)
			)
		)
		(fp_text user "Author: Antmicro"
			(at -0.95 -4.169 -90)
			(layer "B.Fab")
			(hide yes)
			(effects
				(font
					(size 0.7 0.7)
					(thickness 0.15)
				)
				(justify left bottom mirror)
			)
		)
		(fp_text user "License: Apache-2.0"
			(at -0.95 -5.169 -90)
			(layer "B.Fab")
			(hide yes)
			(effects
				(font
					(size 0.7 0.7)
					(thickness 0.15)
				)
				(justify left bottom mirror)
			)
		)
		(pad "1" smd roundrect
			(at -0.48 0 90)
			(size 0.59 0.64)
			(layers "B.Cu" "B.Paste" "B.Mask")
			(roundrect_rratio 0.25)
			(net 518 "/HDMI/HDMI_SDA_5V")
			(pintype "passive")
		)
		(pad "2" smd roundrect
			(at 0.48 0 90)
			(size 0.59 0.64)
			(layers "B.Cu" "B.Paste" "B.Mask")
			(roundrect_rratio 0.25)
			(net 498 "/HDMI/5V_HDMI")
			(pintype "passive")
		)
	)
	(footprint "antmicro-footprints:R_Array_4x0201_Panasonic_EXB18V"
		(layer "B.Cu")
		(at 108.88 74.66 -90)
		(property "Reference" "R122"
			(at 1.54 0.68 90)
			(layer "B.SilkS")
			(effects
				(font
					(size 0.7 0.7)
					(thickness 0.15)
				)
				(justify right bottom mirror)
			)
		)
		(property "Value" "R_4x0R_0201_array"
			(at -1.1 -1.8 90)
			(layer "B.Fab")
			(effects
				(font
					(size 0.7 0.7)
					(thickness 0.15)
				)
				(justify left bottom mirror)
			)
		)
		(property "Footprint" "antmicro-footprints:R_Array_4x0201_Panasonic_EXB18V"
			(at 0 0 -90)
			(layer "F.Fab")
			(hide yes)
			(effects
				(font
					(size 1.27 1.27)
					(thickness 0.15)
				)
			)
		)
		(property "Datasheet" "http://industrial.panasonic.com/cdbs/www-data/pdf/AOC0000/AOC0000C14.pdf"
			(at 0 0 -90)
			(layer "F.Fab")
			(hide yes)
			(effects
				(font
					(size 1.27 1.27)
					(thickness 0.15)
				)
			)
		)
		(property "Author" "Antmicro"
			(at 34.22 183.54 0)
			(layer "B.Fab")
			(hide yes)
			(effects
				(font
					(size 1 1)
					(thickness 0.15)
				)
				(justify mirror)
			)
		)
		(property "License" "Apache-2.0"
			(at 34.22 183.54 0)
			(layer "B.Fab")
			(hide yes)
			(effects
				(font
					(size 1 1)
					(thickness 0.15)
				)
				(justify mirror)
			)
		)
		(property "MPN" "EXB-18VR000X"
			(at 34.22 183.54 0)
			(layer "B.Fab")
			(hide yes)
			(effects
				(font
					(size 1 1)
					(thickness 0.15)
				)
				(justify mirror)
			)
		)
		(property "Manufacturer" "Panasonic"
			(at 34.22 183.54 0)
			(layer "B.Fab")
			(hide yes)
			(effects
				(font
					(size 1 1)
					(thickness 0.15)
				)
				(justify mirror)
			)
		)
		(property "Val" "4x0R_0201"
			(at 34.22 183.54 0)
			(layer "B.Fab")
			(hide yes)
			(effects
				(font
					(size 1 1)
					(thickness 0.15)
				)
				(justify mirror)
			)
		)
		(sheetname "CSI")
		(sheetfile "csi.kicad_sch")
		(attr smd exclude_from_pos_files exclude_from_bom dnp)
		(fp_line
			(start -0.8 -0.45)
			(end -0.8 0.45)
			(stroke
				(width 0.12)
				(type solid)
			)
			(layer "B.SilkS")
		)
		(fp_line
			(start 0.8 -0.45)
			(end 0.8 0.45)
			(stroke
				(width 0.12)
				(type solid)
			)
			(layer "B.SilkS")
		)
		(fp_rect
			(start -0.898 0.66)
			(end 0.898 -0.65)
			(stroke
				(width 0.05)
				(type solid)
			)
			(fill none)
			(layer "B.CrtYd")
		)
		(fp_text user "License: Apache-2.0"
			(at -1.051 -6 90)
			(layer "B.Fab")
			(hide yes)
			(effects
				(font
					(size 0.7 0.7)
					(thickness 0.15)
				)
				(justify left bottom mirror)
			)
		)
		(fp_text user "Author: Antmicro"
			(at -1.051 -4.599 90)
			(layer "B.Fab")
			(hide yes)
			(effects
				(font
					(size 0.7 0.7)
					(thickness 0.15)
				)
				(justify left bottom mirror)
			)
		)
		(fp_text user "${REFERENCE}"
			(at -1.051 -3.2 90)
			(layer "B.Fab")
			(hide yes)
			(effects
				(font
					(size 0.7 0.7)
					(thickness 0.15)
				)
				(justify left bottom mirror)
			)
		)
		(pad "1" smd roundrect
			(at -0.6 -0.298 270)
			(size 0.2 0.4)
			(layers "B.Cu" "B.Paste" "B.Mask")
			(roundrect_rratio 0.25)
			(net 24 "CSI3_D1_P")
			(pinfunction "R1.1")
			(pintype "passive")
		)
		(pad "2" smd roundrect
			(at -0.202 -0.298 270)
			(size 0.2 0.4)
			(layers "B.Cu" "B.Paste" "B.Mask")
			(roundrect_rratio 0.25)
			(net 22 "CSI3_D1_N")
			(pinfunction "R2.1")
			(pintype "passive")
		)
		(pad "3" smd roundrect
			(at 0.2 -0.298 270)
			(size 0.2 0.4)
			(layers "B.Cu" "B.Paste" "B.Mask")
			(roundrect_rratio 0.25)
			(net 16 "CSI3_D0_P")
			(pinfunction "R3.1")
			(pintype "passive")
		)
		(pad "4" smd roundrect
			(at 0.598 -0.298 270)
			(size 0.2 0.4)
			(layers "B.Cu" "B.Paste" "B.Mask")
			(roundrect_rratio 0.25)
			(net 14 "CSI3_D0_N")
			(pinfunction "R4.1")
			(pintype "passive")
		)
		(pad "5" smd roundrect
			(at 0.598 0.3 270)
			(size 0.2 0.4)
			(layers "B.Cu" "B.Paste" "B.Mask")
			(roundrect_rratio 0.25)
			(net 240 "/CSI/CSI3_1_D0_N")
			(pinfunction "R4.2")
			(pintype "passive")
		)
		(pad "6" smd roundrect
			(at 0.2 0.3 270)
			(size 0.2 0.4)
			(layers "B.Cu" "B.Paste" "B.Mask")
			(roundrect_rratio 0.25)
			(net 241 "/CSI/CSI3_1_D0_P")
			(pinfunction "R3.2")
			(pintype "passive")
		)
		(pad "7" smd roundrect
			(at -0.202 0.3 270)
			(size 0.2 0.4)
			(layers "B.Cu" "B.Paste" "B.Mask")
			(roundrect_rratio 0.25)
			(net 238 "/CSI/CSI3_1_D1_N")
			(pinfunction "R2.2")
			(pintype "passive")
		)
		(pad "8" smd roundrect
			(at -0.6 0.3 270)
			(size 0.2 0.4)
			(layers "B.Cu" "B.Paste" "B.Mask")
			(roundrect_rratio 0.25)
			(net 239 "/CSI/CSI3_1_D1_P")
			(pinfunction "R1.2")
			(pintype "passive")
		)
	)
	(footprint "antmicro-footprints:C_0402_1005Metric"
		(layer "B.Cu")
		(at 49.75 115 180)
		(descr "Capacitor SMD 0402")
		(tags "capacitor SMD 0402")
		(property "Reference" "C31"
			(at 13.147849 -9.408333 0)
			(layer "B.SilkS")
			(effects
				(font
					(size 0.7 0.7)
					(thickness 0.15)
				)
				(justify left bottom mirror)
			)
		)
		(property "Value" "C_100n_0402"
			(at 0 -1.4 0)
			(layer "B.Fab")
			(effects
				(font
					(size 0.7 0.7)
					(thickness 0.15)
				)
				(justify left bottom mirror)
			)
		)
		(property "Footprint" "antmicro-footprints:C_0402_1005Metric"
			(at 0 0 180)
			(layer "F.Fab")
			(hide yes)
			(effects
				(font
					(size 1.27 1.27)
					(thickness 0.15)
				)
			)
		)
		(property "Datasheet" "https://www.murata.com/products/productdetail?partno=GRM155R61H104KE14%23"
			(at 0 0 180)
			(layer "F.Fab")
			(hide yes)
			(effects
				(font
					(size 1.27 1.27)
					(thickness 0.15)
				)
			)
		)
		(property "Author" "Antmicro"
			(at 99.5 230 0)
			(layer "B.Fab")
			(hide yes)
			(effects
				(font
					(size 1 1)
					(thickness 0.15)
				)
				(justify mirror)
			)
		)
		(property "Dielectric" "X5R"
			(at 99.5 230 0)
			(layer "B.Fab")
			(hide yes)
			(effects
				(font
					(size 1 1)
					(thickness 0.15)
				)
				(justify mirror)
			)
		)
		(property "License" "Apache-2.0"
			(at 99.5 230 0)
			(layer "B.Fab")
			(hide yes)
			(effects
				(font
					(size 1 1)
					(thickness 0.15)
				)
				(justify mirror)
			)
		)
		(property "MPN" "GRM155R61H104KE14D"
			(at 99.5 230 0)
			(layer "B.Fab")
			(hide yes)
			(effects
				(font
					(size 1 1)
					(thickness 0.15)
				)
				(justify mirror)
			)
		)
		(property "Manufacturer" "Murata"
			(at 99.5 230 0)
			(layer "B.Fab")
			(hide yes)
			(effects
				(font
					(size 1 1)
					(thickness 0.15)
				)
				(justify mirror)
			)
		)
		(property "Val" "100n"
			(at 99.5 230 0)
			(layer "B.Fab")
			(hide yes)
			(effects
				(font
					(size 1 1)
					(thickness 0.15)
				)
				(justify mirror)
			)
		)
		(property "Voltage" "50V"
			(at 99.5 230 0)
			(layer "B.Fab")
			(hide yes)
			(effects
				(font
					(size 1 1)
					(thickness 0.15)
				)
				(justify mirror)
			)
		)
		(sheetname "USB Debug, DP")
		(sheetfile "usb.kicad_sch")
		(attr smd)
		(fp_rect
			(start -0.925 0.47)
			(end 0.925 -0.47)
			(stroke
				(width 0.05)
				(type default)
			)
			(fill none)
			(layer "B.CrtYd")
		)
		(fp_line
			(start 0.504 0.25)
			(end -0.494 0.25)
			(stroke
				(width 0.15)
				(type solid)
			)
			(layer "B.Fab")
		)
		(fp_line
			(start 0.504 -0.248)
			(end 0.504 0.25)
			(stroke
				(width 0.15)
				(type solid)
			)
			(layer "B.Fab")
		)
		(fp_line
			(start -0.494 0.25)
			(end -0.494 -0.248)
			(stroke
				(width 0.15)
				(type solid)
			)
			(layer "B.Fab")
		)
		(fp_line
			(start -0.494 -0.248)
			(end 0.504 -0.248)
			(stroke
				(width 0.15)
				(type solid)
			)
			(layer "B.Fab")
		)
		(fp_text user "${REFERENCE}"
			(at -0.932 -3.168 0)
			(layer "B.Fab")
			(hide yes)
			(effects
				(font
					(size 0.7 0.7)
					(thickness 0.15)
				)
				(justify left bottom mirror)
			)
		)
		(fp_text user "License: Apache-2.0"
			(at -0.932 -5.17 0)
			(layer "B.Fab")
			(hide yes)
			(effects
				(font
					(size 0.7 0.7)
					(thickness 0.15)
				)
				(justify left bottom mirror)
			)
		)
		(fp_text user "Author: Antmicro"
			(at -0.932 -4.17 0)
			(layer "B.Fab")
			(hide yes)
			(effects
				(font
					(size 0.7 0.7)
					(thickness 0.15)
				)
				(justify left bottom mirror)
			)
		)
		(pad "1" smd roundrect
			(at -0.48 0 180)
			(size 0.59 0.64)
			(layers "B.Cu" "B.Paste" "B.Mask")
			(roundrect_rratio 0.25)
			(net 126 "Net-(U5-~{RESET})")
			(pintype "passive")
		)
		(pad "2" smd roundrect
			(at 0.48 0 180)
			(size 0.59 0.64)
			(layers "B.Cu" "B.Paste" "B.Mask")
			(roundrect_rratio 0.25)
			(net 1 "GND")
			(pintype "passive")
		)
	)
	(footprint "antmicro-footprints:R_0402_1005Metric"
		(layer "B.Cu")
		(at 55.125 86.475)
		(descr "Resistor SMD 0402")
		(tags "resistor SMD 0402")
		(property "Reference" "R150"
			(at -1.245 2.525 0)
			(layer "B.SilkS")
			(effects
				(font
					(size 0.7 0.7)
					(thickness 0.15)
				)
				(justify right top mirror)
			)
		)
		(property "Value" "R_10k_0402"
			(at 0 -1.4 0)
			(layer "B.Fab")
			(effects
				(font
					(size 0.7 0.7)
					(thickness 0.15)
				)
				(justify right top mirror)
			)
		)
		(property "Footprint" "antmicro-footprints:R_0402_1005Metric"
			(at 0 0 0)
			(layer "F.Fab")
			(hide yes)
			(effects
				(font
					(size 1.27 1.27)
					(thickness 0.15)
				)
			)
		)
		(property "Datasheet" "https://www.bourns.com/docs/product-datasheets/cr.pdf"
			(at 0 0 0)
			(layer "F.Fab")
			(hide yes)
			(effects
				(font
					(size 1.27 1.27)
					(thickness 0.15)
				)
			)
		)
		(property "Author" "Antmicro"
			(at -31.575 145.225 90)
			(layer "B.Fab")
			(hide yes)
			(effects
				(font
					(size 1 1)
					(thickness 0.15)
				)
				(justify mirror)
			)
		)
		(property "License" "Apache-2.0"
			(at -31.575 145.225 90)
			(layer "B.Fab")
			(hide yes)
			(effects
				(font
					(size 1 1)
					(thickness 0.15)
				)
				(justify mirror)
			)
		)
		(property "MPN" "CR0402-FX-1002GLF"
			(at -31.575 145.225 90)
			(layer "B.Fab")
			(hide yes)
			(effects
				(font
					(size 1 1)
					(thickness 0.15)
				)
				(justify mirror)
			)
		)
		(property "Manufacturer" "Bourns"
			(at -31.575 145.225 90)
			(layer "B.Fab")
			(hide yes)
			(effects
				(font
					(size 1 1)
					(thickness 0.15)
				)
				(justify mirror)
			)
		)
		(property "Tolerance" "1%"
			(at -31.575 145.225 90)
			(layer "B.Fab")
			(hide yes)
			(effects
				(font
					(size 1 1)
					(thickness 0.15)
				)
				(justify mirror)
			)
		)
		(property "Val" "10k"
			(at -31.575 145.225 90)
			(layer "B.Fab")
			(hide yes)
			(effects
				(font
					(size 1 1)
					(thickness 0.15)
				)
				(justify mirror)
			)
		)
		(sheetname "Ethernet")
		(sheetfile "ethernet.kicad_sch")
		(attr smd exclude_from_pos_files exclude_from_bom dnp)
		(fp_rect
			(start -0.925 0.47)
			(end 0.925 -0.47)
			(stroke
				(width 0.05)
				(type default)
			)
			(fill none)
			(layer "B.CrtYd")
		)
		(fp_rect
			(start -0.5 0.25)
			(end 0.5 -0.25)
			(stroke
				(width 0.15)
				(type solid)
			)
			(fill none)
			(layer "B.Fab")
		)
		(fp_text user "Author: Antmicro"
			(at -0.95 -4.169 0)
			(layer "B.Fab")
			(hide yes)
			(effects
				(font
					(size 0.7 0.7)
					(thickness 0.15)
				)
				(justify right top mirror)
			)
		)
		(fp_text user "License: Apache-2.0"
			(at -0.95 -5.169 0)
			(layer "B.Fab")
			(hide yes)
			(effects
				(font
					(size 0.7 0.7)
					(thickness 0.15)
				)
				(justify right top mirror)
			)
		)
		(fp_text user "${REFERENCE}"
			(at -0.95 -3.168 0)
			(layer "B.Fab")
			(hide yes)
			(effects
				(font
					(size 0.7 0.7)
					(thickness 0.15)
				)
				(justify right top mirror)
			)
		)
		(pad "1" smd roundrect
			(at -0.48 0)
			(size 0.59 0.64)
			(layers "B.Cu" "B.Paste" "B.Mask")
			(roundrect_rratio 0.25)
			(net 573 "/Ethernet/TPL")
			(pintype "passive")
		)
		(pad "2" smd roundrect
			(at 0.48 0)
			(size 0.59 0.64)
			(layers "B.Cu" "B.Paste" "B.Mask")
			(roundrect_rratio 0.25)
			(net 105 "/Ethernet/VDD")
			(pintype "passive")
		)
	)
)
